FILE_TYPE = MULTI_PHYS_TABLE;

PART 'ADM1086AKSZREEL7'

{========================================================================================}
:VALUE               | PART_TYPE | MATERIAL | PART_NUMBER    = STANDARD        | LIFECYCLE          | PART_NUMBER   | JEDEC_TYPE             | DESCRIPTION                           | MANUFTR | MANUF_PN            | RD_CMPLS_LVL | CMPLS_LVL | FROM_PJ     | CLASS | DIP_SMD | DATA                        | EE_CHECK_LIST | FP_ECN                  | PSL | CREATOR | STATUS | MSD  | ESD_CDM | ESD_HBM | ESD_MM | PIN_LENGTH_SHORT_PIN | PIN_LENGTH_LONG_PIN | CREATEDAY  ;
{========================================================================================}
 'ADM1086AKSZ-REEL7' | 'SMLF'    | 'IC'     | 'AL001086001'(!) = 'End of Design' | 'Comp-Approve'   | 'AL001086001' |'SC70-6_0-65_2X1-25XA'| 'IC OTHER(6P)ADM1086AKSZ-REEL7(SC70)' | 'ADV'   | 'ADM1086AKSZ-REEL7' | 'EP(V1)'     | ''        | 'S9S-CHRIS' | 'IC'  | ''      | 'ADV_ADM1086AKSZ-REEL7.pdf' | ''            | 'ADM1086AKSZ-REEL7.msg' | ''  | ''      | ''     | 'NA' | 'NA'    | 'NA'    | 'NA'   | '0 MILS'             | '0 MILS'            | '20200525'
 'ADM1086AKSZ-REEL7' | 'SMLF'    | 'EMPTY'  | 'AL001086001'(!) = 'End of Design' | 'Comp-Approve'   | 'AL001086001' |'SC70-6_0-65_2X1-25XA'| 'IC OTHER(6P)ADM1086AKSZ-REEL7(SC70)' | 'ADV'   | 'ADM1086AKSZ-REEL7' | 'EP(V1)'     | ''        | 'S9S-CHRIS' | 'IC'  | ''      | 'ADV_ADM1086AKSZ-REEL7.pdf' | ''            | 'ADM1086AKSZ-REEL7.msg' | ''  | ''      | ''     | 'NA' | 'NA'    | 'NA'    | 'NA'   | '0 MILS'             | '0 MILS'            | '20200525'

END_PART

END.

